# BASEBOARD_FAB2 (Tioga Pass) — schematic netlist excerpt (pin names and nets, part order shuffled) for the footprints in the layout excerpt that follows; sources: Cadence DE-HDL packaged netlist, KiCad conversion of Wiwynn_Tioga_Pass_MB.brd

J1G3  SCONN288_H44441004  SCONN  pkg PIP  page 81
  \12v\(1)  = P12V_NVDIMM_GHJ
  VSS(93)  = GND
  DQ(4)  = M_J_DQ<5>
  VSS(92)  = GND
  DQ(0)  = M_J_DQ<1>
  VSS(91)  = GND
  DQS9P  = M_J_DQS_DP<9>
  DQS9N  = M_J_DQS_DN<9>
  VSS(90)  = GND
  DQ(6)  = M_J_DQ<7>
  VSS(89)  = GND
  DQ(2)  = M_J_DQ<3>
  VSS(88)  = GND
  DQ(12)  = M_J_DQ<13>
  VSS(87)  = GND
  DQ(8)  = M_J_DQ<9>
  VSS(86)  = GND
  DQS10P  = M_J_DQS_DP<10>
  DQS10N  = M_J_DQS_DN<10>
  VSS(85)  = GND
  DQ(14)  = M_J_DQ<15>
  VSS(84)  = GND
  DQ(10)  = M_J_DQ<11>
  VSS(83)  = GND
  DQ(20)  = M_J_DQ<21>
  VSS(82)  = GND
  DQ(16)  = M_J_DQ<17>
  VSS(81)  = GND
  DQS11P  = M_J_DQS_DP<11>
  DQS11N  = M_J_DQS_DN<11>
  VSS(80)  = GND
  DQ(22)  = M_J_DQ<23>
  VSS(79)  = GND
  DQ(18)  = M_J_DQ<19>
  VSS(78)  = GND
  DQ(28)  = M_J_DQ<29>
  VSS(77)  = GND
  DQ(24)  = M_J_DQ<25>
  VSS(76)  = GND
  DQS12P  = M_J_DQS_DP<12>
  DQS12N  = M_J_DQS_DN<12>
  VSS(75)  = GND
  DQ(30)  = M_J_DQ<31>
  VSS(74)  = GND
  DQ(26)  = M_J_DQ<27>
  VSS(73)  = GND
  CB(4)  = M_J_ECC<5>
  VSS(72)  = GND
  CB(0)  = M_J_ECC<1>
  VSS(71)  = GND
  DQS17P  = M_J_DQS_DP<17>
  DQS17N  = M_J_DQS_DN<17>
  VSS(70)  = GND
  CB(6)  = M_J_ECC<7>
  VSS(69)  = GND
  CB(2)  = M_J_ECC<3>
  VSS(68)  = GND
  RESET_N  = M_GHJ_RST_N
  VDD(25)  = PVDDQ_GHJ
  CKE(0)  = M_J_CKE<0>
  VDD(24)  = PVDDQ_GHJ
  ACT_N  = M_J_ACT_N
  BG(0)  = M_J_BG<0>
  VDD(23)  = PVDDQ_GHJ
  A12  = M_J_MA<12>
  A9  = M_J_MA<9>
  VDD(22)  = PVDDQ_GHJ
  A8  = M_J_MA<8>
  A6  = M_J_MA<6>
  VDD(21)  = PVDDQ_GHJ
  A3  = M_J_MA<3>
  A1  = M_J_MA<1>
  VDD(20)  = PVDDQ_GHJ
  CK0P  = M_J_CLK_DP<0>
  CK0N  = M_J_CLK_DN<0>
  VDD(19)  = PVDDQ_GHJ
  VTT(1)  = PVTT_GHJ
  EVENT_N  = FM_DIMM_EVENT_COD_N
  A0  = M_J_MA<0>
  VDD(18)  = PVDDQ_GHJ
  BA(0)  = M_J_BA<0>
  A16_RAS_N  = M_J_MA<16>
  VDD(17)  = PVDDQ_GHJ
  S0_N  = M_J_CS_N<0>
  VDD(16)  = PVDDQ_GHJ
  A15_CAS_N  = M_J_MA<15>
  ODT(0)  = M_J_ODT<0>
  VDD(15)  = PVDDQ_GHJ
  S1_N  = M_J_CS_N<1>
  VDD(14)  = PVDDQ_GHJ
  ODT(1)  = M_J_ODT<1>
  VDD(13)  = PVDDQ_GHJ
  S2_N_C(0)  = M_J_CS_N<2>
  VSS(67)  = GND
  DQ(36)  = M_J_DQ<37>
  VSS(66)  = GND
  DQ(32)  = M_J_DQ<33>
  VSS(65)  = GND
  DQS13P  = M_J_DQS_DP<13>
  DQS13N  = M_J_DQS_DN<13>
  VSS(64)  = GND
  DQ(38)  = M_J_DQ<39>
  VSS(63)  = GND
  DQ(34)  = M_J_DQ<35>
  VSS(62)  = GND
  DQ(44)  = M_J_DQ<45>
  VSS(61)  = GND
  DQ(40)  = M_J_DQ<41>
  VSS(60)  = GND
  DQS14P  = M_J_DQS_DP<14>
  DQS14N  = M_J_DQS_DN<14>
  VSS(59)  = GND
  DQ(46)  = M_J_DQ<47>
  VSS(58)  = GND
  DQ(42)  = M_J_DQ<43>
  VSS(57)  = GND
  DQ(52)  = M_J_DQ<53>
  VSS(56)  = GND
  DQ(48)  = M_J_DQ<49>
  VSS(55)  = GND
  DQS15P  = M_J_DQS_DP<15>
  DQS15N  = M_J_DQS_DN<15>
  VSS(54)  = GND
  DQ(54)  = M_J_DQ<55>
  VSS(53)  = GND
  DQ(50)  = M_J_DQ<51>
  VSS(52)  = GND
  DQ(60)  = M_J_DQ<61>
  VSS(51)  = GND
  DQ(56)  = M_J_DQ<57>
  VSS(50)  = GND
  DQS16P  = M_J_DQS_DP<16>
  DQS16N  = M_J_DQS_DN<16>
  VSS(49)  = GND
  DQ(62)  = M_J_DQ<63>
  VSS(48)  = GND
  DQ(58)  = M_J_DQ<59>
  VSS(47)  = GND
  SA(0)  = GND
  SA(1)  = GND
  SCL  = SMB_DDR_GHJ_VPP_SCL
  VPP(4)  = PVPP_GHJ
  VPP(3)  = PVPP_GHJ
  RFU(2)  = TP_CH_J_DIMM_J0_RFU_2
  \12v\(0)  = P12V_NVDIMM_GHJ
  VREFCA  = M_J_VREF
  VSS(46)  = GND
  DQ(5)  = M_J_DQ<4>
  VSS(45)  = GND
  DQ(1)  = M_J_DQ<0>
  VSS(44)  = GND
  DQS0N  = M_J_DQS_DN<0>
  DQS0P  = M_J_DQS_DP<0>
  VSS(43)  = GND
  DQ(7)  = M_J_DQ<6>
  VSS(42)  = GND
  DQ(3)  = M_J_DQ<2>
  VSS(41)  = GND
  DQ(13)  = M_J_DQ<12>
  VSS(40)  = GND
  DQ(9)  = M_J_DQ<8>
  VSS(39)  = GND
  DQS1N  = M_J_DQS_DN<1>
  DQS1P  = M_J_DQS_DP<1>
  VSS(38)  = GND
  DQ(15)  = M_J_DQ<14>
  VSS(37)  = GND
  DQ(11)  = M_J_DQ<10>
  VSS(36)  = GND
  DQ(21)  = M_J_DQ<20>
  VSS(35)  = GND
  DQ(17)  = M_J_DQ<16>
  VSS(34)  = GND
  DQS2N  = M_J_DQS_DN<2>
  DQS2P  = M_J_DQS_DP<2>
  VSS(33)  = GND
  DQ(23)  = M_J_DQ<22>
  VSS(32)  = GND
  DQ(19)  = M_J_DQ<18>
  VSS(31)  = GND
  DQ(29)  = M_J_DQ<28>
  VSS(30)  = GND
  DQ(25)  = M_J_DQ<24>
  VSS(29)  = GND
  DQS3N  = M_J_DQS_DN<3>
  DQS3P  = M_J_DQS_DP<3>
  VSS(28)  = GND
  DQ(31)  = M_J_DQ<30>
  VSS(27)  = GND
  DQ(27)  = M_J_DQ<26>
  VSS(26)  = GND
  CB(5)  = M_J_ECC<4>
  VSS(25)  = GND
  CB(1)  = M_J_ECC<0>
  VSS(24)  = GND
  DQS8N  = M_J_DQS_DN<8>
  DQS8P  = M_J_DQS_DP<8>
  VSS(23)  = GND
  CB(7)  = M_J_ECC<6>
  VSS(22)  = GND
  CB(3)  = M_J_ECC<2>
  VSS(21)  = GND
  CKE(1)  = M_J_CKE<1>
  VDD(12)  = PVDDQ_GHJ
  RFU(0)  = TP_CH_J_DIMM_J0_RFU_0
  VDD(11)  = PVDDQ_GHJ
  BG(1)  = M_J_BG<1>
  ALERT_N  = M_J_ALERT_N
  VDD(10)  = PVDDQ_GHJ
  A11  = M_J_MA<11>
  A7  = M_J_MA<7>
  VDD(9)  = PVDDQ_GHJ
  A5  = M_J_MA<5>
  A4  = M_J_MA<4>
  VDD(8)  = PVDDQ_GHJ
  A2  = M_J_MA<2>
  VDD(7)  = PVDDQ_GHJ
  CK1P  = M_J_CLK_DP<1>
  CK1N  = M_J_CLK_DN<1>
  VDD(6)  = PVDDQ_GHJ
  VTT(0)  = PVTT_GHJ
  PAR  = M_J_PAR
  VDD(5)  = PVDDQ_GHJ
  BA(1)  = M_J_BA<1>
  A10  = M_J_MA<10>
  VDD(4)  = PVDDQ_GHJ
  RFU(1)  = TP_CH_J_DIMM_J0_RFU_1
  A14_WE_N  = M_J_MA<14>
  VDD(3)  = PVDDQ_GHJ
  SAVE_N_NC  = FM_ADR_COMPLETE_GHJ_N
  VDD(2)  = PVDDQ_GHJ
  A13  = M_J_MA<13>
  VDD(1)  = PVDDQ_GHJ
  A17  = M_J_MA<17>
  C(2)  = M_J_C<2>
  VDD(0)  = PVDDQ_GHJ
  S3_N_C(1)  = M_J_CS_N<3>
  SA(2)  = PVPP_GHJ
  VSS(20)  = GND
  DQ(37)  = M_J_DQ<36>
  VSS(19)  = GND
  DQ(33)  = M_J_DQ<32>
  VSS(18)  = GND
  DQS4N  = M_J_DQS_DN<4>
  DQS4P  = M_J_DQS_DP<4>
  VSS(17)  = GND
  DQ(39)  = M_J_DQ<38>
  VSS(16)  = GND
  DQ(35)  = M_J_DQ<34>
  VSS(15)  = GND
  DQ(45)  = M_J_DQ<44>
  VSS(14)  = GND
  DQ(41)  = M_J_DQ<40>
  VSS(13)  = GND
  DQS5N  = M_J_DQS_DN<5>
  DQS5P  = M_J_DQS_DP<5>
  VSS(12)  = GND
  DQ(47)  = M_J_DQ<46>
  VSS(11)  = GND
  DQ(43)  = M_J_DQ<42>
  VSS(10)  = GND
  DQ(53)  = M_J_DQ<52>
  VSS(9)  = GND
  DQ(49)  = M_J_DQ<48>
  VSS(8)  = GND
  DQS6N  = M_J_DQS_DN<6>
  DQS6P  = M_J_DQS_DP<6>
  VSS(7)  = GND
  DQ(55)  = M_J_DQ<54>
  VSS(6)  = GND
  DQ(51)  = M_J_DQ<50>
  VSS(5)  = GND
  DQ(61)  = M_J_DQ<60>
  VSS(4)  = GND
  DQ(57)  = M_J_DQ<56>
  VSS(3)  = GND
  DQS7N  = M_J_DQS_DN<7>
  DQS7P  = M_J_DQS_DP<7>
  VSS(2)  = GND
  DQ(63)  = M_J_DQ<62>
  VSS(1)  = GND
  DQ(59)  = M_J_DQ<58>
  VSS(0)  = GND
  VDDSPD  = PVPP_GHJ
  SDA  = SMB_DDR_GHJ_VPP_SDA
  VPP(1)  = PVPP_GHJ
  VPP(0)  = PVPP_GHJ
  VPP(2)  = PVPP_GHJ

(kicad_pcb
	(version 20260206)
	(generator "pcbnew")
	(generator_version "10.0")
	(general
		(thickness 1.6)
		(legacy_teardrops no)
	)
	(paper "A4")
	(title_block
		(title "Wiwynn_Tioga_Pass_MB.brd")
		(comment 1 "Tioga Pass / footprint 437 of 4770 (J1G3), pads 102-152 of 291")
	)
	(layers
		(0 "F.Cu" signal "TOP")
		(4 "In1.Cu" signal "L2GND")
		(6 "In2.Cu" signal "L3")
		(8 "In3.Cu" signal "L4GND")
		(10 "In4.Cu" signal "L5")
		(12 "In5.Cu" signal "L6GND")
		(14 "In6.Cu" signal "L7VCC")
		(16 "In7.Cu" signal "L8VCC")
		(18 "In8.Cu" signal "L9GND")
		(20 "In9.Cu" signal "L10")
		(22 "In10.Cu" signal "L11GND")
		(24 "In11.Cu" signal "L12")
		(26 "In12.Cu" signal "L13GND")
		(2 "B.Cu" signal "BOTTOM")
		(9 "F.Adhes" user "F.Adhesive")
		(11 "B.Adhes" user "B.Adhesive")
		(13 "F.Paste" user "Package Geometry/Pastemask Top")
		(15 "B.Paste" user "Package Geometry/Pastemask Bottom")
		(5 "F.SilkS" user "Ref Des/Silkscreen Top")
		(7 "B.SilkS" user "Ref Des/Silkscreen Bottom")
		(1 "F.Mask" user "Board Geometry/Soldermask Top")
		(3 "B.Mask" user "Board Geometry/Soldermask Bottom")
		(17 "Dwgs.User" user "User.Drawings")
		(19 "Cmts.User" user "User.Comments")
		(21 "Eco1.User" user "User.Eco1")
		(23 "Eco2.User" user "User.Eco2")
		(25 "Edge.Cuts" user "Board Geometry/Outline")
		(27 "Margin" user)
		(31 "F.CrtYd" user "Package Geometry/Place Bound Top")
		(29 "B.CrtYd" user "Package Geometry/Place Bound Bottom")
		(35 "F.Fab" user "Ref Des/Assembly Top")
		(33 "B.Fab" user "Ref Des/Assembly Bottom")
	)
	(footprint ""
		(layer "F.Cu")
		(at 29.699458 3.778758 90)
		(property "Reference" "J1G3"
			(at 7.054088 34.562542 0)
			(unlocked yes)
			(layer "F.SilkS")
			(effects
				(font
					(size 0.7874 0.5842)
					(thickness 0.1524)
				)
				(justify left)
			)
		)
		(property "Value" ""
			(at 0 0 90)
			(layer "F.Fab")
			(effects
				(font
					(size 1.27 1.27)
				)
			)
		)
		(duplicate_pad_numbers_are_jumpers no)
		(pad "99" smd rect
			(at 0 88.399874 90)
			(size 1.8034 0.508)
			(layers "F.Cu" "F.Mask" "F.Paste")
			(net "M_J_DQS_DP<13>")
		)
		(pad "100" smd rect
			(at 0 89.250012 90)
			(size 1.8034 0.508)
			(layers "F.Cu" "F.Mask" "F.Paste")
			(net "M_J_DQS_DN<13>")
		)
		(pad "101" smd rect
			(at 0 90.099896 90)
			(size 1.8034 0.508)
			(layers "F.Cu" "F.Mask" "F.Paste")
			(net "GND")
		)
		(pad "102" smd rect
			(at 0 90.950034 90)
			(size 1.8034 0.508)
			(layers "F.Cu" "F.Mask" "F.Paste")
			(net "M_J_DQ<39>")
		)
		(pad "103" smd rect
			(at 0 91.799918 90)
			(size 1.8034 0.508)
			(layers "F.Cu" "F.Mask" "F.Paste")
			(net "GND")
		)
		(pad "104" smd rect
			(at 0 92.650056 90)
			(size 1.8034 0.508)
			(layers "F.Cu" "F.Mask" "F.Paste")
			(net "M_J_DQ<35>")
		)
		(pad "105" smd rect
			(at 0 93.49994 90)
			(size 1.8034 0.508)
			(layers "F.Cu" "F.Mask" "F.Paste")
			(net "GND")
		)
		(pad "106" smd rect
			(at 0 94.350078 90)
			(size 1.8034 0.508)
			(layers "F.Cu" "F.Mask" "F.Paste")
			(net "M_J_DQ<45>")
		)
		(pad "107" smd rect
			(at 0 95.199962 90)
			(size 1.8034 0.508)
			(layers "F.Cu" "F.Mask" "F.Paste")
			(net "GND")
		)
		(pad "108" smd rect
			(at 0 96.0501 90)
			(size 1.8034 0.508)
			(layers "F.Cu" "F.Mask" "F.Paste")
			(net "M_J_DQ<41>")
		)
		(pad "109" smd rect
			(at 0 96.899984 90)
			(size 1.8034 0.508)
			(layers "F.Cu" "F.Mask" "F.Paste")
			(net "GND")
		)
		(pad "110" smd rect
			(at 0 97.750122 90)
			(size 1.8034 0.508)
			(layers "F.Cu" "F.Mask" "F.Paste")
			(net "M_J_DQS_DP<14>")
		)
		(pad "111" smd rect
			(at 0 98.600006 90)
			(size 1.8034 0.508)
			(layers "F.Cu" "F.Mask" "F.Paste")
			(net "M_J_DQS_DN<14>")
		)
		(pad "112" smd rect
			(at 0 99.44989 90)
			(size 1.8034 0.508)
			(layers "F.Cu" "F.Mask" "F.Paste")
			(net "GND")
		)
		(pad "113" smd rect
			(at 0 100.300028 90)
			(size 1.8034 0.508)
			(layers "F.Cu" "F.Mask" "F.Paste")
			(net "M_J_DQ<47>")
		)
		(pad "114" smd rect
			(at 0 101.149912 90)
			(size 1.8034 0.508)
			(layers "F.Cu" "F.Mask" "F.Paste")
			(net "GND")
		)
		(pad "115" smd rect
			(at 0 102.00005 90)
			(size 1.8034 0.508)
			(layers "F.Cu" "F.Mask" "F.Paste")
			(net "M_J_DQ<43>")
		)
		(pad "116" smd rect
			(at 0 102.849934 90)
			(size 1.8034 0.508)
			(layers "F.Cu" "F.Mask" "F.Paste")
			(net "GND")
		)
		(pad "117" smd rect
			(at 0 103.700072 90)
			(size 1.8034 0.508)
			(layers "F.Cu" "F.Mask" "F.Paste")
			(net "M_J_DQ<53>")
		)
		(pad "118" smd rect
			(at 0 104.549956 90)
			(size 1.8034 0.508)
			(layers "F.Cu" "F.Mask" "F.Paste")
			(net "GND")
		)
		(pad "119" smd rect
			(at 0 105.400094 90)
			(size 1.8034 0.508)
			(layers "F.Cu" "F.Mask" "F.Paste")
			(net "M_J_DQ<49>")
		)
		(pad "120" smd rect
			(at 0 106.249978 90)
			(size 1.8034 0.508)
			(layers "F.Cu" "F.Mask" "F.Paste")
			(net "GND")
		)
		(pad "121" smd rect
			(at 0 107.100116 90)
			(size 1.8034 0.508)
			(layers "F.Cu" "F.Mask" "F.Paste")
			(net "M_J_DQS_DP<15>")
		)
		(pad "122" smd rect
			(at 0 107.95 90)
			(size 1.8034 0.508)
			(layers "F.Cu" "F.Mask" "F.Paste")
			(net "M_J_DQS_DN<15>")
		)
		(pad "123" smd rect
			(at 0 108.799884 90)
			(size 1.8034 0.508)
			(layers "F.Cu" "F.Mask" "F.Paste")
			(net "GND")
		)
		(pad "124" smd rect
			(at 0 109.650022 90)
			(size 1.8034 0.508)
			(layers "F.Cu" "F.Mask" "F.Paste")
			(net "M_J_DQ<55>")
		)
		(pad "125" smd rect
			(at 0 110.499906 90)
			(size 1.8034 0.508)
			(layers "F.Cu" "F.Mask" "F.Paste")
			(net "GND")
		)
		(pad "126" smd rect
			(at 0 111.350044 90)
			(size 1.8034 0.508)
			(layers "F.Cu" "F.Mask" "F.Paste")
			(net "M_J_DQ<51>")
		)
		(pad "127" smd rect
			(at 0 112.199928 90)
			(size 1.8034 0.508)
			(layers "F.Cu" "F.Mask" "F.Paste")
			(net "GND")
		)
		(pad "128" smd rect
			(at 0 113.050066 90)
			(size 1.8034 0.508)
			(layers "F.Cu" "F.Mask" "F.Paste")
			(net "M_J_DQ<61>")
		)
		(pad "129" smd rect
			(at 0 113.89995 90)
			(size 1.8034 0.508)
			(layers "F.Cu" "F.Mask" "F.Paste")
			(net "GND")
		)
		(pad "130" smd rect
			(at 0 114.750088 90)
			(size 1.8034 0.508)
			(layers "F.Cu" "F.Mask" "F.Paste")
			(net "M_J_DQ<57>")
		)
		(pad "131" smd rect
			(at 0 115.599972 90)
			(size 1.8034 0.508)
			(layers "F.Cu" "F.Mask" "F.Paste")
			(net "GND")
		)
		(pad "132" smd rect
			(at 0 116.45011 90)
			(size 1.8034 0.508)
			(layers "F.Cu" "F.Mask" "F.Paste")
			(net "M_J_DQS_DP<16>")
		)
		(pad "133" smd rect
			(at 0 117.299994 90)
			(size 1.8034 0.508)
			(layers "F.Cu" "F.Mask" "F.Paste")
			(net "M_J_DQS_DN<16>")
		)
		(pad "134" smd rect
			(at 0 118.149878 90)
			(size 1.8034 0.508)
			(layers "F.Cu" "F.Mask" "F.Paste")
			(net "GND")
		)
		(pad "135" smd rect
			(at 0 119.000016 90)
			(size 1.8034 0.508)
			(layers "F.Cu" "F.Mask" "F.Paste")
			(net "M_J_DQ<63>")
		)
		(pad "136" smd rect
			(at 0 119.8499 90)
			(size 1.8034 0.508)
			(layers "F.Cu" "F.Mask" "F.Paste")
			(net "GND")
		)
		(pad "137" smd rect
			(at 0 120.700038 90)
			(size 1.8034 0.508)
			(layers "F.Cu" "F.Mask" "F.Paste")
			(net "M_J_DQ<59>")
		)
		(pad "138" smd rect
			(at 0 121.549922 90)
			(size 1.8034 0.508)
			(layers "F.Cu" "F.Mask" "F.Paste")
			(net "GND")
		)
		(pad "139" smd rect
			(at 0 122.40006 90)
			(size 1.8034 0.508)
			(layers "F.Cu" "F.Mask" "F.Paste")
			(net "GND")
		)
		(pad "140" smd rect
			(at 0 123.249944 90)
			(size 1.8034 0.508)
			(layers "F.Cu" "F.Mask" "F.Paste")
			(net "GND")
		)
		(pad "141" smd rect
			(at 0 124.100082 90)
			(size 1.8034 0.508)
			(layers "F.Cu" "F.Mask" "F.Paste")
			(net "SMB_DDR_GHJ_VPP_SCL")
		)
		(pad "142" smd rect
			(at 0 124.949966 90)
			(size 1.8034 0.508)
			(layers "F.Cu" "F.Mask" "F.Paste")
			(net "PVPP_GHJ")
		)
		(pad "143" smd rect
			(at 0 125.800104 90)
			(size 1.8034 0.508)
			(layers "F.Cu" "F.Mask" "F.Paste")
			(net "PVPP_GHJ")
		)
		(pad "144" smd rect
			(at 0 126.649988 90)
			(size 1.8034 0.508)
			(layers "F.Cu" "F.Mask" "F.Paste")
			(net "TP_CH_J_DIMM_J0_RFU_2")
		)
		(pad "145" smd rect
			(at 4.59994 0 90)
			(size 1.8034 0.508)
			(layers "F.Cu" "F.Mask" "F.Paste")
			(net "P12V_NVDIMM_GHJ")
		)
		(pad "146" smd rect
			(at 4.59994 0.849884 90)
			(size 1.8034 0.508)
			(layers "F.Cu" "F.Mask" "F.Paste")
			(net "M_J_VREF")
		)
		(pad "147" smd rect
			(at 4.59994 1.700022 90)
			(size 1.8034 0.508)
			(layers "F.Cu" "F.Mask" "F.Paste")
			(net "GND")
		)
		(pad "148" smd rect
			(at 4.59994 2.549906 90)
			(size 1.8034 0.508)
			(layers "F.Cu" "F.Mask" "F.Paste")
			(net "M_J_DQ<4>")
		)
		(pad "149" smd rect
			(at 4.59994 3.400044 90)
			(size 1.8034 0.508)
			(layers "F.Cu" "F.Mask" "F.Paste")
			(net "GND")
		)
	)
)
